# T6G (Grand Teton) — schematic netlist excerpt (pin names and nets, part order shuffled) for the footprints in the layout excerpt that follows; sources: Cadence DE-HDL packaged netlist, KiCad conversion of 04192023_DAF0TMB3IC0_F0TG_MB_C_brd_V02_OCP.brd

R600  Q_RES  0 5% CHIP  pkg 0402LF  page 77 : A = SPI_CPU0_LVC3_CS1_N ; B = SPI_CPU0_LVC3_SCM_CS1_N
R577  Q_RES  10K 1% CHIP  pkg 0402LF  page 134 : A = P3V3_AUX ; B = HP_LVC3_OCP_SFF_PRSNT2_N

(kicad_pcb
	(version 20260206)
	(generator "pcbnew")
	(generator_version "10.0")
	(general
		(thickness 1.6)
		(legacy_teardrops no)
	)
	(paper "A4")
	(title_block
		(title "04192023_DAF0TMB3IC0_F0TG_MB_C_brd_V02_OCP.brd")
		(comment 1 "Grand Teton / footprints 584-585 of 8354")
	)
	(layers
		(0 "F.Cu" signal "TOP")
		(4 "In1.Cu" signal "GND")
		(6 "In2.Cu" signal "IN1")
		(8 "In3.Cu" signal "GND1")
		(10 "In4.Cu" signal "IN2")
		(12 "In5.Cu" signal "GND2")
		(14 "In6.Cu" signal "IN3")
		(16 "In7.Cu" signal "GND3")
		(18 "In8.Cu" signal "VCC")
		(20 "In9.Cu" signal "VCC1")
		(22 "In10.Cu" signal "GND4")
		(24 "In11.Cu" signal "IN4")
		(26 "In12.Cu" signal "GND5")
		(28 "In13.Cu" signal "IN5")
		(30 "In14.Cu" signal "GND6")
		(32 "In15.Cu" signal "IN6")
		(34 "In16.Cu" signal "GND7")
		(2 "B.Cu" signal "BOTTOM")
		(9 "F.Adhes" user "F.Adhesive")
		(11 "B.Adhes" user "B.Adhesive")
		(13 "F.Paste" user "Package Geometry/Pastemask Top")
		(15 "B.Paste" user "Package Geometry/Pastemask Bottom")
		(5 "F.SilkS" user "Ref Des/Silkscreen Top")
		(7 "B.SilkS" user "Ref Des/Silkscreen Bottom")
		(1 "F.Mask" user "Board Geometry/Soldermask Top")
		(3 "B.Mask" user "Board Geometry/Soldermask Bottom")
		(17 "Dwgs.User" user "User.Drawings")
		(19 "Cmts.User" user "User.Comments")
		(21 "Eco1.User" user "User.Eco1")
		(23 "Eco2.User" user "User.Eco2")
		(25 "Edge.Cuts" user "Board Geometry/Outline")
		(27 "Margin" user)
		(31 "F.CrtYd" user "Package Geometry/Place Bound Top")
		(29 "B.CrtYd" user "Package Geometry/Place Bound Bottom")
		(35 "F.Fab" user "Ref Des/Assembly Top")
		(33 "B.Fab" user "Ref Des/Assembly Bottom")
	)
	(footprint ""
		(layer "F.Cu")
		(at 463.370168 -109.646212 180)
		(property "Reference" "R577"
			(at 0 0 180)
			(layer "F.SilkS")
			(hide yes)
			(effects
				(font
					(size 1.27 1.27)
				)
			)
		)
		(property "Value" ""
			(at 0 0 180)
			(layer "F.Fab")
			(effects
				(font
					(size 1.27 1.27)
				)
			)
		)
		(duplicate_pad_numbers_are_jumpers no)
		(fp_line
			(start 0.7874 0.4064)
			(end -0.7874 0.4064)
			(stroke
				(width 0.1524)
				(type default)
			)
			(layer "F.SilkS")
		)
		(fp_line
			(start 0.7874 -0.4064)
			(end 0.7874 0.4064)
			(stroke
				(width 0.1524)
				(type default)
			)
			(layer "F.SilkS")
		)
		(fp_line
			(start -0.7874 0.4064)
			(end -0.7874 -0.4064)
			(stroke
				(width 0.1524)
				(type default)
			)
			(layer "F.SilkS")
		)
		(fp_line
			(start -0.7874 -0.4064)
			(end 0.7874 -0.4064)
			(stroke
				(width 0.1524)
				(type default)
			)
			(layer "F.SilkS")
		)
		(fp_line
			(start 0.67945 0.3048)
			(end 0.120396 0.3048)
			(stroke
				(width 0.1)
				(type default)
			)
			(layer "F.Fab")
		)
		(fp_line
			(start 0.67945 -0.3048)
			(end 0.67945 0.3048)
			(stroke
				(width 0.1)
				(type default)
			)
			(layer "F.Fab")
		)
		(fp_line
			(start 0.12065 -0.2794)
			(end 0.12065 -0.3048)
			(stroke
				(width 0.1)
				(type default)
			)
			(layer "F.Fab")
		)
		(fp_line
			(start 0.12065 -0.3048)
			(end 0.67945 -0.3048)
			(stroke
				(width 0.1)
				(type default)
			)
			(layer "F.Fab")
		)
		(fp_line
			(start 0.120396 0.3048)
			(end 0.120396 0.2794)
			(stroke
				(width 0.1)
				(type default)
			)
			(layer "F.Fab")
		)
		(fp_line
			(start 0.120396 0.2794)
			(end -0.12065 0.2794)
			(stroke
				(width 0.1)
				(type default)
			)
			(layer "F.Fab")
		)
		(fp_line
			(start -0.12065 0.3048)
			(end -0.67945 0.3048)
			(stroke
				(width 0.1)
				(type default)
			)
			(layer "F.Fab")
		)
		(fp_line
			(start -0.12065 0.2794)
			(end -0.12065 0.3048)
			(stroke
				(width 0.1)
				(type default)
			)
			(layer "F.Fab")
		)
		(fp_line
			(start -0.12065 -0.2794)
			(end 0.12065 -0.2794)
			(stroke
				(width 0.1)
				(type default)
			)
			(layer "F.Fab")
		)
		(fp_line
			(start -0.12065 -0.305054)
			(end -0.12065 -0.2794)
			(stroke
				(width 0.1)
				(type default)
			)
			(layer "F.Fab")
		)
		(fp_line
			(start -0.67945 0.3048)
			(end -0.67945 -0.305054)
			(stroke
				(width 0.1)
				(type default)
			)
			(layer "F.Fab")
		)
		(fp_line
			(start -0.67945 -0.305054)
			(end -0.12065 -0.305054)
			(stroke
				(width 0.1)
				(type default)
			)
			(layer "F.Fab")
		)
		(pad "1" smd circle
			(at -0.40005 0 180)
			(size 0 0)
			(layers "F.Cu" "F.Mask" "F.Paste")
			(net "P3V3_AUX")
		)
		(pad "2" smd circle
			(at 0.40005 0 180)
			(size 0 0)
			(layers "F.Cu" "F.Mask" "F.Paste")
			(net "HP_LVC3_OCP_SFF_PRSNT2_N")
		)
	)
	(footprint ""
		(layer "F.Cu")
		(at 253.506224 -133.622796 180)
		(property "Reference" "R600"
			(at 0 0 180)
			(layer "F.SilkS")
			(hide yes)
			(effects
				(font
					(size 1.27 1.27)
				)
			)
		)
		(property "Value" ""
			(at 0 0 180)
			(layer "F.Fab")
			(effects
				(font
					(size 1.27 1.27)
				)
			)
		)
		(duplicate_pad_numbers_are_jumpers no)
		(fp_line
			(start 0.7874 0.4064)
			(end -0.7874 0.4064)
			(stroke
				(width 0.1524)
				(type default)
			)
			(layer "F.SilkS")
		)
		(fp_line
			(start 0.7874 -0.4064)
			(end 0.7874 0.4064)
			(stroke
				(width 0.1524)
				(type default)
			)
			(layer "F.SilkS")
		)
		(fp_line
			(start -0.7874 0.4064)
			(end -0.7874 -0.4064)
			(stroke
				(width 0.1524)
				(type default)
			)
			(layer "F.SilkS")
		)
		(fp_line
			(start -0.7874 -0.4064)
			(end 0.7874 -0.4064)
			(stroke
				(width 0.1524)
				(type default)
			)
			(layer "F.SilkS")
		)
		(fp_line
			(start 0.67945 0.3048)
			(end 0.120396 0.3048)
			(stroke
				(width 0.1)
				(type default)
			)
			(layer "F.Fab")
		)
		(fp_line
			(start 0.67945 -0.3048)
			(end 0.67945 0.3048)
			(stroke
				(width 0.1)
				(type default)
			)
			(layer "F.Fab")
		)
		(fp_line
			(start 0.12065 -0.2794)
			(end 0.12065 -0.3048)
			(stroke
				(width 0.1)
				(type default)
			)
			(layer "F.Fab")
		)
		(fp_line
			(start 0.12065 -0.3048)
			(end 0.67945 -0.3048)
			(stroke
				(width 0.1)
				(type default)
			)
			(layer "F.Fab")
		)
		(fp_line
			(start 0.120396 0.3048)
			(end 0.120396 0.2794)
			(stroke
				(width 0.1)
				(type default)
			)
			(layer "F.Fab")
		)
		(fp_line
			(start 0.120396 0.2794)
			(end -0.12065 0.2794)
			(stroke
				(width 0.1)
				(type default)
			)
			(layer "F.Fab")
		)
		(fp_line
			(start -0.12065 0.3048)
			(end -0.67945 0.3048)
			(stroke
				(width 0.1)
				(type default)
			)
			(layer "F.Fab")
		)
		(fp_line
			(start -0.12065 0.2794)
			(end -0.12065 0.3048)
			(stroke
				(width 0.1)
				(type default)
			)
			(layer "F.Fab")
		)
		(fp_line
			(start -0.12065 -0.2794)
			(end 0.12065 -0.2794)
			(stroke
				(width 0.1)
				(type default)
			)
			(layer "F.Fab")
		)
		(fp_line
			(start -0.12065 -0.305054)
			(end -0.12065 -0.2794)
			(stroke
				(width 0.1)
				(type default)
			)
			(layer "F.Fab")
		)
		(fp_line
			(start -0.67945 0.3048)
			(end -0.67945 -0.305054)
			(stroke
				(width 0.1)
				(type default)
			)
			(layer "F.Fab")
		)
		(fp_line
			(start -0.67945 -0.305054)
			(end -0.12065 -0.305054)
			(stroke
				(width 0.1)
				(type default)
			)
			(layer "F.Fab")
		)
		(pad "1" smd circle
			(at -0.40005 0 180)
			(size 0 0)
			(layers "F.Cu" "F.Mask" "F.Paste")
			(net "SPI_CPU0_LVC3_CS1_N")
		)
		(pad "2" smd circle
			(at 0.40005 0 180)
			(size 0 0)
			(layers "F.Cu" "F.Mask" "F.Paste")
			(net "SPI_CPU0_LVC3_SCM_CS1_N")
		)
	)
)
